# T6G (Grand Teton) — schematic netlist excerpt (pin names and nets, part order shuffled) for the footprints in the layout excerpt that follows; sources: Cadence DE-HDL packaged netlist, KiCad conversion of 04192023_DAF0TMB3IC0_F0TG_MB_C_brd_V02_OCP.brd

PC2187  Q_CAP  1UF 25V 10% X6S  pkg C0402  page 262 : A = HSC_VDD_R ; B = AGND_HSC
R5019  Q_RES  1K 1% EMPTY  pkg 0402LF  page 159 : A = PVDD11_S3_P1 ; B = I3C_SCM_2_R_SDA

(kicad_pcb
	(version 20260206)
	(generator "pcbnew")
	(generator_version "10.0")
	(general
		(thickness 1.6)
		(legacy_teardrops no)
	)
	(paper "A4")
	(title_block
		(title "04192023_DAF0TMB3IC0_F0TG_MB_C_brd_V02_OCP.brd")
		(comment 1 "Grand Teton / footprints 1242-1243 of 8354")
	)
	(layers
		(0 "F.Cu" signal "TOP")
		(4 "In1.Cu" signal "GND")
		(6 "In2.Cu" signal "IN1")
		(8 "In3.Cu" signal "GND1")
		(10 "In4.Cu" signal "IN2")
		(12 "In5.Cu" signal "GND2")
		(14 "In6.Cu" signal "IN3")
		(16 "In7.Cu" signal "GND3")
		(18 "In8.Cu" signal "VCC")
		(20 "In9.Cu" signal "VCC1")
		(22 "In10.Cu" signal "GND4")
		(24 "In11.Cu" signal "IN4")
		(26 "In12.Cu" signal "GND5")
		(28 "In13.Cu" signal "IN5")
		(30 "In14.Cu" signal "GND6")
		(32 "In15.Cu" signal "IN6")
		(34 "In16.Cu" signal "GND7")
		(2 "B.Cu" signal "BOTTOM")
		(9 "F.Adhes" user "F.Adhesive")
		(11 "B.Adhes" user "B.Adhesive")
		(13 "F.Paste" user "Package Geometry/Pastemask Top")
		(15 "B.Paste" user "Package Geometry/Pastemask Bottom")
		(5 "F.SilkS" user "Ref Des/Silkscreen Top")
		(7 "B.SilkS" user "Ref Des/Silkscreen Bottom")
		(1 "F.Mask" user "Board Geometry/Soldermask Top")
		(3 "B.Mask" user "Board Geometry/Soldermask Bottom")
		(17 "Dwgs.User" user "User.Drawings")
		(19 "Cmts.User" user "User.Comments")
		(21 "Eco1.User" user "User.Eco1")
		(23 "Eco2.User" user "User.Eco2")
		(25 "Edge.Cuts" user "Board Geometry/Outline")
		(27 "Margin" user)
		(31 "F.CrtYd" user "Package Geometry/Place Bound Top")
		(29 "B.CrtYd" user "Package Geometry/Place Bound Bottom")
		(35 "F.Fab" user "Ref Des/Assembly Top")
		(33 "B.Fab" user "Ref Des/Assembly Bottom")
	)
	(footprint ""
		(layer "F.Cu")
		(at 178.71694 -402.468842 180)
		(property "Reference" "PC2187"
			(at 0 0 180)
			(layer "F.SilkS")
			(hide yes)
			(effects
				(font
					(size 1.27 1.27)
				)
			)
		)
		(property "Value" ""
			(at 0 0 180)
			(layer "F.Fab")
			(effects
				(font
					(size 1.27 1.27)
				)
			)
		)
		(duplicate_pad_numbers_are_jumpers no)
		(fp_line
			(start 0.7874 0.4064)
			(end -0.7874 0.4064)
			(stroke
				(width 0.1524)
				(type default)
			)
			(layer "F.SilkS")
		)
		(fp_line
			(start 0.7874 -0.4064)
			(end 0.7874 0.4064)
			(stroke
				(width 0.1524)
				(type default)
			)
			(layer "F.SilkS")
		)
		(fp_line
			(start -0.7874 0.4064)
			(end -0.7874 -0.4064)
			(stroke
				(width 0.1524)
				(type default)
			)
			(layer "F.SilkS")
		)
		(fp_line
			(start -0.7874 -0.4064)
			(end 0.7874 -0.4064)
			(stroke
				(width 0.1524)
				(type default)
			)
			(layer "F.SilkS")
		)
		(fp_line
			(start 0.67945 0.3048)
			(end 0.120396 0.3048)
			(stroke
				(width 0.1)
				(type default)
			)
			(layer "F.Fab")
		)
		(fp_line
			(start 0.67945 -0.3048)
			(end 0.67945 0.3048)
			(stroke
				(width 0.1)
				(type default)
			)
			(layer "F.Fab")
		)
		(fp_line
			(start 0.12065 -0.2794)
			(end 0.12065 -0.3048)
			(stroke
				(width 0.1)
				(type default)
			)
			(layer "F.Fab")
		)
		(fp_line
			(start 0.12065 -0.3048)
			(end 0.67945 -0.3048)
			(stroke
				(width 0.1)
				(type default)
			)
			(layer "F.Fab")
		)
		(fp_line
			(start 0.120396 0.3048)
			(end 0.120396 0.2794)
			(stroke
				(width 0.1)
				(type default)
			)
			(layer "F.Fab")
		)
		(fp_line
			(start 0.120396 0.2794)
			(end -0.12065 0.2794)
			(stroke
				(width 0.1)
				(type default)
			)
			(layer "F.Fab")
		)
		(fp_line
			(start -0.12065 0.3048)
			(end -0.67945 0.3048)
			(stroke
				(width 0.1)
				(type default)
			)
			(layer "F.Fab")
		)
		(fp_line
			(start -0.12065 0.2794)
			(end -0.12065 0.3048)
			(stroke
				(width 0.1)
				(type default)
			)
			(layer "F.Fab")
		)
		(fp_line
			(start -0.12065 -0.2794)
			(end 0.12065 -0.2794)
			(stroke
				(width 0.1)
				(type default)
			)
			(layer "F.Fab")
		)
		(fp_line
			(start -0.12065 -0.305054)
			(end -0.12065 -0.2794)
			(stroke
				(width 0.1)
				(type default)
			)
			(layer "F.Fab")
		)
		(fp_line
			(start -0.67945 0.3048)
			(end -0.67945 -0.305054)
			(stroke
				(width 0.1)
				(type default)
			)
			(layer "F.Fab")
		)
		(fp_line
			(start -0.67945 -0.305054)
			(end -0.12065 -0.305054)
			(stroke
				(width 0.1)
				(type default)
			)
			(layer "F.Fab")
		)
		(pad "1" smd circle
			(at -0.40005 0 180)
			(size 0 0)
			(layers "F.Cu" "F.Mask" "F.Paste")
			(net "HSC_VDD_R")
		)
		(pad "2" smd circle
			(at 0.40005 0 180)
			(size 0 0)
			(layers "F.Cu" "F.Mask" "F.Paste")
			(net "AGND_HSC")
		)
	)
	(footprint ""
		(layer "F.Cu")
		(at 42.637964 -173.938946 180)
		(property "Reference" "R5019"
			(at 0 0 180)
			(layer "F.SilkS")
			(hide yes)
			(effects
				(font
					(size 1.27 1.27)
				)
			)
		)
		(property "Value" ""
			(at 0 0 180)
			(layer "F.Fab")
			(effects
				(font
					(size 1.27 1.27)
				)
			)
		)
		(duplicate_pad_numbers_are_jumpers no)
		(fp_line
			(start 0.7874 0.4064)
			(end -0.7874 0.4064)
			(stroke
				(width 0.1524)
				(type default)
			)
			(layer "F.SilkS")
		)
		(fp_line
			(start 0.7874 -0.4064)
			(end 0.7874 0.4064)
			(stroke
				(width 0.1524)
				(type default)
			)
			(layer "F.SilkS")
		)
		(fp_line
			(start -0.7874 0.4064)
			(end -0.7874 -0.4064)
			(stroke
				(width 0.1524)
				(type default)
			)
			(layer "F.SilkS")
		)
		(fp_line
			(start -0.7874 -0.4064)
			(end 0.7874 -0.4064)
			(stroke
				(width 0.1524)
				(type default)
			)
			(layer "F.SilkS")
		)
		(fp_line
			(start 0.67945 0.3048)
			(end 0.120396 0.3048)
			(stroke
				(width 0.1)
				(type default)
			)
			(layer "F.Fab")
		)
		(fp_line
			(start 0.67945 -0.3048)
			(end 0.67945 0.3048)
			(stroke
				(width 0.1)
				(type default)
			)
			(layer "F.Fab")
		)
		(fp_line
			(start 0.12065 -0.2794)
			(end 0.12065 -0.3048)
			(stroke
				(width 0.1)
				(type default)
			)
			(layer "F.Fab")
		)
		(fp_line
			(start 0.12065 -0.3048)
			(end 0.67945 -0.3048)
			(stroke
				(width 0.1)
				(type default)
			)
			(layer "F.Fab")
		)
		(fp_line
			(start 0.120396 0.3048)
			(end 0.120396 0.2794)
			(stroke
				(width 0.1)
				(type default)
			)
			(layer "F.Fab")
		)
		(fp_line
			(start 0.120396 0.2794)
			(end -0.12065 0.2794)
			(stroke
				(width 0.1)
				(type default)
			)
			(layer "F.Fab")
		)
		(fp_line
			(start -0.12065 0.3048)
			(end -0.67945 0.3048)
			(stroke
				(width 0.1)
				(type default)
			)
			(layer "F.Fab")
		)
		(fp_line
			(start -0.12065 0.2794)
			(end -0.12065 0.3048)
			(stroke
				(width 0.1)
				(type default)
			)
			(layer "F.Fab")
		)
		(fp_line
			(start -0.12065 -0.2794)
			(end 0.12065 -0.2794)
			(stroke
				(width 0.1)
				(type default)
			)
			(layer "F.Fab")
		)
		(fp_line
			(start -0.12065 -0.305054)
			(end -0.12065 -0.2794)
			(stroke
				(width 0.1)
				(type default)
			)
			(layer "F.Fab")
		)
		(fp_line
			(start -0.67945 0.3048)
			(end -0.67945 -0.305054)
			(stroke
				(width 0.1)
				(type default)
			)
			(layer "F.Fab")
		)
		(fp_line
			(start -0.67945 -0.305054)
			(end -0.12065 -0.305054)
			(stroke
				(width 0.1)
				(type default)
			)
			(layer "F.Fab")
		)
		(pad "1" smd circle
			(at -0.40005 0 180)
			(size 0 0)
			(layers "F.Cu" "F.Mask" "F.Paste")
			(net "PVDD11_S3_P1")
		)
		(pad "2" smd circle
			(at 0.40005 0 180)
			(size 0 0)
			(layers "F.Cu" "F.Mask" "F.Paste")
			(net "I3C_SCM_2_R_SDA")
		)
	)
)
